FILE_TYPE = MACRO_DRAWING;
SET COLOR_WIRE YELLOW;
SET COLOR_PROP MONO;
SET COLOR_DOT WHITE;
SET COLOR_ARC YELLOW;
SET COLOR_BODY GREEN;
SET COLOR_NOTE MONO;
SET PROP_DISPLAY VALUE;
SET PAGE_NUMBER P140;
FORCEADD M25PE16..1
(-2350 2700);
FORCEPROP 0 LAST GROUP NI_I210&RJ45
J 0
(-2647 2287);
DISPLAY 0.638298 (-2647 2287);
PAINT BROWN (-2647 2287);
DISPLAY BOTH (-2647 2287);
FORCEPROP 1 LAST PART_NUMBER H77797-001
J 0
(-2650 2350);
DISPLAY 0.617021 (-2650 2350);
PAINT BLUE (-2650 2350);
FORCEPROP 2 LASTPIN (-2700 2500) $PN 3
J 2
(-2710 2510);
DISPLAY 0.617021 (-2710 2510);
PAINT ORANGE (-2710 2510);
FORCEPROP 2 LASTPIN (-2700 2550) $PN 1
J 2
(-2710 2560);
DISPLAY 0.617021 (-2710 2560);
PAINT ORANGE (-2710 2560);
FORCEPROP 2 LASTPIN (-2700 2650) $PN 6
J 2
(-2710 2660);
DISPLAY 0.617021 (-2710 2660);
PAINT ORANGE (-2710 2660);
FORCEPROP 2 LASTPIN (-2700 2600) $PN 7
J 2
(-2710 2610);
DISPLAY 0.617021 (-2710 2610);
PAINT ORANGE (-2710 2610);
FORCEPROP 2 LASTPIN (-2700 2850) $PN 8
J 2
(-2710 2860);
DISPLAY 0.617021 (-2710 2860);
PAINT ORANGE (-2710 2860);
FORCEPROP 2 LASTPIN (-2000 2500) $PN 4
J 0
(-1990 2510);
DISPLAY 0.617021 (-1990 2510);
PAINT ORANGE (-1990 2510);
FORCEPROP 2 LASTPIN (-2000 2750) $PN 2
J 0
(-1990 2760);
DISPLAY 0.617021 (-1990 2760);
PAINT ORANGE (-1990 2760);
FORCEPROP 2 LASTPIN (-2700 2750) $PN 5
J 2
(-2710 2760);
DISPLAY 0.617021 (-2710 2760);
PAINT ORANGE (-2710 2760);
FORCEPROP 1 LAST MATERIAL IC
J 0
(-2400 3025);
DISPLAY 0.617021 (-2400 3025);
PAINT SKYBLUE (-2400 3025);
FORCEPROP 1 LAST LOCATION U9E1
J 1
(-2525 3025);
DISPLAY 0.617021 (-2525 3025);
PAINT AQUA (-2525 3025);
FORCEPROP 2 LAST CDS_LIB mstr_memory
J 0
(-2350 2700);
PAINT ORANGE (-2350 2700);
DISPLAY INVISIBLE (-2350 2700);
FORCEPROP 1 LAST PATH I1
J 0
(-2300 3050);
PAINT GREEN (-2300 3050);
DISPLAY INVISIBLE (-2300 3050);
FORCEPROP 1 LAST PACK_TYPE SM
J 0
(-2650 3150);
PAINT SKYBLUE (-2650 3150);
DISPLAY INVISIBLE (-2650 3150);
FORCEPROP 2 LAST CDS_LOCATION U9E1
J 1
(-2175 3075);
DISPLAY 0.617021 (-2175 3075);
PAINT AQUA (-2175 3075);
DISPLAY INVISIBLE (-2175 3075);
FORCEPROP 2 LAST ROOM NIC_SPRV
J 0
(-2300 4100);
DISPLAY 1.021277 (-2300 4100);
PAINT ORANGE (-2300 4100);
DISPLAY INVISIBLE (-2300 4100);
FORCEPROP 2 LAST SEC 1
J 0
(-2300 4100);
DISPLAY 0.680851 (-2300 4100);
PAINT MONO (-2300 4100);
DISPLAY INVISIBLE (-2300 4100);
FORCEPROP 2 LAST SEC_TYPE SM
J 0
(-2300 4100);
DISPLAY 1.021277 (-2300 4100);
PAINT ORANGE (-2300 4100);
DISPLAY INVISIBLE (-2300 4100);
FORCEPROP 2 LAST BOM_COST NT_GBE_BASE
J 0
(-2300 4150);
DISPLAY 1.021277 (-2300 4150);
PAINT ORANGE (-2300 4150);
DISPLAY INVISIBLE (-2300 4150);
FORCEADD RES..2
(-3200 3300);
FORCEPROP 1 LAST VALUE 3.32K
J 0
(-3155 3375);
DISPLAY 0.617021 (-3155 3375);
PAINT SKYBLUE (-3155 3375);
FORCEPROP 1 LAST WATTAGE 1/16W
J 0
(-3160 3275);
DISPLAY 0.617021 (-3160 3275);
PAINT SKYBLUE (-3160 3275);
FORCEPROP 1 LAST MATERIAL CHIP
J 0
(-3160 3225);
DISPLAY 0.617021 (-3160 3225);
PAINT SKYBLUE (-3160 3225);
FORCEPROP 1 LAST PART_NUMBER G21796-027
J 0
(-3160 3175);
DISPLAY 0.617021 (-3160 3175);
PAINT BLUE (-3160 3175);
FORCEPROP 1 LAST PACK_TYPE 0402
J 0
(-3160 3125);
DISPLAY 0.617021 (-3160 3125);
PAINT SKYBLUE (-3160 3125);
FORCEPROP 1 LASTPIN (-3200 3200) $PN 2
J 0
(-3195 3210);
DISPLAY 0.617021 (-3195 3210);
PAINT ORANGE (-3195 3210);
FORCEPROP 1 LAST TOLERANCE 1%
J 0
(-3155 3325);
DISPLAY 0.617021 (-3155 3325);
PAINT SKYBLUE (-3155 3325);
FORCEPROP 1 LASTPIN (-3200 3400) $PN 1
J 0
(-3195 3362);
DISPLAY 0.617021 (-3195 3362);
PAINT ORANGE (-3195 3362);
FORCEPROP 1 LAST LOCATION R1R9
J 0
(-3155 3425);
DISPLAY 0.617021 (-3155 3425);
PAINT AQUA (-3155 3425);
FORCEPROP 0 LAST GROUP NI_I210&RJ45
J 0
(-3147 3062);
DISPLAY 0.638298 (-3147 3062);
PAINT BROWN (-3147 3062);
DISPLAY BOTH (-3147 3062);
FORCEPROP 2 LAST CDS_LIB mstr_discrete
J 0
(-3200 3300);
PAINT ORANGE (-3200 3300);
DISPLAY INVISIBLE (-3200 3300);
FORCEPROP 1 LAST PATH I10
J 0
(-3150 3475);
DISPLAY 0.978723 (-3150 3475);
PAINT WHITE (-3150 3475);
DISPLAY INVISIBLE (-3150 3475);
FORCEPROP 2 LAST ROOM NIC_SPRV
J 0
(-3150 3475);
DISPLAY 1.021277 (-3150 3475);
PAINT ORANGE (-3150 3475);
DISPLAY INVISIBLE (-3150 3475);
FORCEPROP 2 LAST SEC 1
J 0
(-3150 3525);
PAINT MONO (-3150 3525);
DISPLAY INVISIBLE (-3150 3525);
FORCEPROP 2 LAST CDS_LOCATION R1R9
J 0
(-3155 3425);
DISPLAY 0.617021 (-3155 3425);
PAINT AQUA (-3155 3425);
DISPLAY INVISIBLE (-3155 3425);
FORCEPROP 2 LAST BOM_COST NT_GBE_BASE
J 0
(-3150 3525);
DISPLAY 1.021277 (-3150 3525);
PAINT ORANGE (-3150 3525);
DISPLAY INVISIBLE (-3150 3525);
FORCEPROP 2 LAST SEC_TYPE 0402
J 0
(-3150 3525);
DISPLAY 1.021277 (-3150 3525);
PAINT ORANGE (-3150 3525);
DISPLAY INVISIBLE (-3150 3525);
FORCEADD RES..2
(-3550 3300);
FORCEPROP 0 LAST GROUP NI_I210&RJ45
J 0
(-3522 3012);
DISPLAY 0.638298 (-3522 3012);
PAINT BROWN (-3522 3012);
DISPLAY BOTH (-3522 3012);
FORCEPROP 1 LASTPIN (-3550 3200) $PN 2
J 0
(-3545 3210);
DISPLAY 0.617021 (-3545 3210);
PAINT ORANGE (-3545 3210);
FORCEPROP 1 LAST TOLERANCE 1%
J 0
(-3505 3325);
DISPLAY 0.617021 (-3505 3325);
PAINT SKYBLUE (-3505 3325);
FORCEPROP 1 LASTPIN (-3550 3400) $PN 1
J 0
(-3545 3362);
DISPLAY 0.617021 (-3545 3362);
PAINT ORANGE (-3545 3362);
FORCEPROP 1 LAST VALUE 3.32K
J 0
(-3505 3375);
DISPLAY 0.617021 (-3505 3375);
PAINT SKYBLUE (-3505 3375);
FORCEPROP 1 LAST LOCATION R1R3
J 0
(-3505 3425);
DISPLAY 0.617021 (-3505 3425);
PAINT AQUA (-3505 3425);
FORCEPROP 1 LAST WATTAGE 1/16W
J 0
(-3510 3275);
DISPLAY 0.617021 (-3510 3275);
PAINT SKYBLUE (-3510 3275);
FORCEPROP 1 LAST MATERIAL CHIP
J 0
(-3510 3225);
DISPLAY 0.617021 (-3510 3225);
PAINT SKYBLUE (-3510 3225);
FORCEPROP 1 LAST PART_NUMBER G21796-027
J 0
(-3510 3175);
DISPLAY 0.617021 (-3510 3175);
PAINT BLUE (-3510 3175);
FORCEPROP 1 LAST PACK_TYPE 0402
J 0
(-3510 3125);
DISPLAY 0.617021 (-3510 3125);
PAINT SKYBLUE (-3510 3125);
FORCEPROP 2 LAST CDS_LIB mstr_discrete
J 0
(-3550 3300);
PAINT ORANGE (-3550 3300);
DISPLAY INVISIBLE (-3550 3300);
FORCEPROP 2 LAST CDS_LOCATION R1R3
J 0
(-3505 3425);
DISPLAY 0.617021 (-3505 3425);
PAINT AQUA (-3505 3425);
DISPLAY INVISIBLE (-3505 3425);
FORCEPROP 1 LAST PATH I11
J 0
(-3500 3475);
DISPLAY 0.978723 (-3500 3475);
PAINT WHITE (-3500 3475);
DISPLAY INVISIBLE (-3500 3475);
FORCEPROP 2 LAST ROOM NIC_SPRV
J 0
(-3500 3475);
DISPLAY 1.021277 (-3500 3475);
PAINT ORANGE (-3500 3475);
DISPLAY INVISIBLE (-3500 3475);
FORCEPROP 2 LAST SEC_TYPE 0402
J 0
(-3500 3525);
DISPLAY 1.021277 (-3500 3525);
PAINT ORANGE (-3500 3525);
DISPLAY INVISIBLE (-3500 3525);
FORCEPROP 2 LAST BOM_COST NT_GBE_BASE
J 0
(-3500 3525);
DISPLAY 1.021277 (-3500 3525);
PAINT ORANGE (-3500 3525);
DISPLAY INVISIBLE (-3500 3525);
FORCEPROP 2 LAST SEC 1
J 0
(-3500 3525);
PAINT MONO (-3500 3525);
DISPLAY INVISIBLE (-3500 3525);
FORCEADD RES..2
(-3950 3300);
FORCEPROP 1 LASTPIN (-3950 3200) $PN 2
J 0
(-3945 3210);
DISPLAY 0.617021 (-3945 3210);
PAINT ORANGE (-3945 3210);
FORCEPROP 1 LAST TOLERANCE 1%
J 0
(-3905 3325);
DISPLAY 0.617021 (-3905 3325);
PAINT SKYBLUE (-3905 3325);
FORCEPROP 1 LASTPIN (-3950 3400) $PN 1
J 0
(-3945 3362);
DISPLAY 0.617021 (-3945 3362);
PAINT ORANGE (-3945 3362);
FORCEPROP 1 LAST VALUE 20.0K
J 0
(-3905 3375);
DISPLAY 0.617021 (-3905 3375);
PAINT SKYBLUE (-3905 3375);
FORCEPROP 1 LAST LOCATION R1R7
J 0
(-3905 3425);
DISPLAY 0.617021 (-3905 3425);
PAINT AQUA (-3905 3425);
FORCEPROP 1 LAST PACK_TYPE 0402
J 0
(-3910 3125);
DISPLAY 0.617021 (-3910 3125);
PAINT SKYBLUE (-3910 3125);
FORCEPROP 1 LAST PART_NUMBER G21796-040
J 0
(-3910 3175);
DISPLAY 0.617021 (-3910 3175);
PAINT BLUE (-3910 3175);
FORCEPROP 1 LAST MATERIAL CHIP
J 0
(-3910 3225);
DISPLAY 0.617021 (-3910 3225);
PAINT SKYBLUE (-3910 3225);
FORCEPROP 1 LAST WATTAGE 1/16W
J 0
(-3910 3275);
DISPLAY 0.617021 (-3910 3275);
PAINT SKYBLUE (-3910 3275);
FORCEPROP 0 LAST GROUP NI_I210&RJ45
J 0
(-3922 3062);
DISPLAY 0.638298 (-3922 3062);
PAINT BROWN (-3922 3062);
DISPLAY BOTH (-3922 3062);
FORCEPROP 2 LAST CDS_LIB mstr_discrete
J 0
(-3950 3300);
PAINT ORANGE (-3950 3300);
DISPLAY INVISIBLE (-3950 3300);
FORCEPROP 2 LAST CDS_LOCATION R1R7
J 0
(-3905 3425);
DISPLAY 0.617021 (-3905 3425);
PAINT AQUA (-3905 3425);
DISPLAY INVISIBLE (-3905 3425);
FORCEPROP 2 LAST ROOM NIC_SPRV
J 0
(-3900 3475);
DISPLAY 1.021277 (-3900 3475);
PAINT ORANGE (-3900 3475);
DISPLAY INVISIBLE (-3900 3475);
FORCEPROP 1 LAST PATH I12
J 0
(-3900 3475);
DISPLAY 0.978723 (-3900 3475);
PAINT WHITE (-3900 3475);
DISPLAY INVISIBLE (-3900 3475);
FORCEPROP 2 LAST SEC 1
J 0
(-3900 3525);
PAINT MONO (-3900 3525);
DISPLAY INVISIBLE (-3900 3525);
FORCEPROP 2 LAST SEC_TYPE 0402
J 0
(-3900 3525);
DISPLAY 1.021277 (-3900 3525);
PAINT ORANGE (-3900 3525);
DISPLAY INVISIBLE (-3900 3525);
FORCEPROP 2 LAST BOM_COST NT_GBE_BASE
J 0
(-3900 3525);
DISPLAY 1.021277 (-3900 3525);
PAINT ORANGE (-3900 3525);
DISPLAY INVISIBLE (-3900 3525);
FORCEADD P3V3_STBY..1
(-3950 3625);
FORCEPROP 3 LASTPIN (-3950 3575) SIG_NAME P3V3_STBY\g
J 0
(-3940 3585);
DISPLAY 0.659574 (-3940 3585);
PAINT MONO (-3940 3585);
DISPLAY INVISIBLE (-3940 3585);
FORCEPROP 1 LAST VOLTAGE 3.3V
J 0
(-3995 3582);
DISPLAY 0.340426 (-3995 3582);
PAINT SKYBLUE (-3995 3582);
DISPLAY INVISIBLE (-3995 3582);
FORCEPROP 1 LAST PATH I13
J 0
(-3905 3627);
DISPLAY 0.340426 (-3905 3627);
PAINT GREEN (-3905 3627);
DISPLAY INVISIBLE (-3905 3627);
FORCEPROP 1 LAST SIZE 1B
J 0
(-3905 3647);
DISPLAY 0.340426 (-3905 3647);
PAINT GREEN (-3905 3647);
DISPLAY INVISIBLE (-3905 3647);
FORCEPROP 2 LAST CDS_LIB mstr_symbols
J 0
(-3950 3625);
PAINT ORANGE (-3950 3625);
DISPLAY INVISIBLE (-3950 3625);
FORCEPROP 1 LAST BODY_TYPE PLUMBING
J 0
(-3995 3582);
DISPLAY 0.340426 (-3995 3582);
PAINT GREEN (-3995 3582);
DISPLAY INVISIBLE (-3995 3582);
FORCEPROP 1 LAST HDL_POWER P3V3_STBY
J 0
(-4250 3500);
DISPLAY 0.872340 (-4250 3500);
PAINT ORANGE (-4250 3500);
DISPLAY INVISIBLE (-4250 3500);
FORCEADD RES..2
(-3825 2350);
FORCEPROP 0 LAST GROUP NI_I210&RJ45
J 0
(-3772 2112);
DISPLAY 0.638298 (-3772 2112);
PAINT BROWN (-3772 2112);
DISPLAY BOTH (-3772 2112);
FORCEPROP 1 LAST LOCATION R1R6
J 0
(-3780 2475);
DISPLAY 0.617021 (-3780 2475);
PAINT AQUA (-3780 2475);
FORCEPROP 1 LAST VALUE 3.32K
J 0
(-3780 2425);
DISPLAY 0.617021 (-3780 2425);
PAINT SKYBLUE (-3780 2425);
FORCEPROP 1 LASTPIN (-3825 2450) $PN 1
J 0
(-3820 2412);
DISPLAY 0.617021 (-3820 2412);
PAINT ORANGE (-3820 2412);
FORCEPROP 1 LAST PACK_TYPE 0402
J 0
(-3785 2175);
DISPLAY 0.617021 (-3785 2175);
PAINT SKYBLUE (-3785 2175);
FORCEPROP 1 LAST PART_NUMBER G21796-027
J 0
(-3785 2225);
DISPLAY 0.617021 (-3785 2225);
PAINT BLUE (-3785 2225);
FORCEPROP 1 LAST TOLERANCE 1%
J 0
(-3780 2375);
DISPLAY 0.617021 (-3780 2375);
PAINT SKYBLUE (-3780 2375);
FORCEPROP 1 LASTPIN (-3825 2250) $PN 2
J 0
(-3820 2260);
DISPLAY 0.617021 (-3820 2260);
PAINT ORANGE (-3820 2260);
FORCEPROP 1 LAST MATERIAL EMPTY
J 0
(-3785 2275);
DISPLAY 0.617021 (-3785 2275);
PAINT RED (-3785 2275);
FORCEPROP 1 LAST WATTAGE 1/16W
J 0
(-3785 2325);
DISPLAY 0.617021 (-3785 2325);
PAINT SKYBLUE (-3785 2325);
FORCEPROP 2 LAST CDS_LIB mstr_discrete
J 0
(-3825 2350);
PAINT ORANGE (-3825 2350);
DISPLAY INVISIBLE (-3825 2350);
FORCEPROP 2 LAST CDS_LOCATION R1R6
J 0
(-3780 2475);
DISPLAY 0.617021 (-3780 2475);
PAINT AQUA (-3780 2475);
DISPLAY INVISIBLE (-3780 2475);
FORCEPROP 2 LAST ROOM NIC_SPRV
J 0
(-3775 2525);
DISPLAY 1.021277 (-3775 2525);
PAINT ORANGE (-3775 2525);
DISPLAY INVISIBLE (-3775 2525);
FORCEPROP 1 LAST PATH I14
J 0
(-3775 2525);
DISPLAY 0.978723 (-3775 2525);
PAINT WHITE (-3775 2525);
DISPLAY INVISIBLE (-3775 2525);
FORCEPROP 2 LAST BOM_COST NT_GBE_BASE
J 0
(-3775 2575);
DISPLAY 1.021277 (-3775 2575);
PAINT ORANGE (-3775 2575);
DISPLAY INVISIBLE (-3775 2575);
FORCEPROP 2 LAST SEC_TYPE 0402
J 0
(-3775 2575);
DISPLAY 1.021277 (-3775 2575);
PAINT ORANGE (-3775 2575);
DISPLAY INVISIBLE (-3775 2575);
FORCEPROP 2 LAST SEC 1
J 0
(-3775 2575);
PAINT MONO (-3775 2575);
DISPLAY INVISIBLE (-3775 2575);
FORCEADD GND..1
(-3825 2075);
FORCEPROP 3 LASTPIN (-3825 2125) SIG_NAME GND\g
J 0
(-3815 2135);
DISPLAY 0.659574 (-3815 2135);
PAINT MONO (-3815 2135);
DISPLAY INVISIBLE (-3815 2135);
FORCEPROP 1 LAST VOLTAGE 0.0V
J 0
(-3870 2032);
DISPLAY 0.340426 (-3870 2032);
PAINT SKYBLUE (-3870 2032);
DISPLAY INVISIBLE (-3870 2032);
FORCEPROP 1 LAST SIZE 1B
J 0
(-3750 2025);
DISPLAY 0.872340 (-3750 2025);
PAINT AQUA (-3750 2025);
DISPLAY INVISIBLE (-3750 2025);
FORCEPROP 1 LAST PATH I16
J 0
(-3750 2075);
DISPLAY 0.872340 (-3750 2075);
PAINT AQUA (-3750 2075);
DISPLAY INVISIBLE (-3750 2075);
FORCEPROP 2 LAST CDS_LIB mstr_symbols
J 0
(-3825 2075);
PAINT ORANGE (-3825 2075);
DISPLAY INVISIBLE (-3825 2075);
FORCEPROP 1 LAST BODY_TYPE PLUMBING
J 0
(-3870 2032);
DISPLAY 0.340426 (-3870 2032);
PAINT GREEN (-3870 2032);
DISPLAY INVISIBLE (-3870 2032);
FORCEPROP 1 LAST HDL_POWER GND
J 0
(-3825 2225);
DISPLAY 0.872340 (-3825 2225);
PAINT GREEN (-3825 2225);
DISPLAY INVISIBLE (-3825 2225);
FORCEADD RES..1
(-1400 2750);
FORCEPROP 1 LAST MATERIAL CHIP
J 0
(-1675 2625);
DISPLAY 0.617021 (-1675 2625);
PAINT SKYBLUE (-1675 2625);
FORCEPROP 1 LAST PART_NUMBER G21796-074
J 0
(-1525 2625);
DISPLAY 0.617021 (-1525 2625);
PAINT BLUE (-1525 2625);
FORCEPROP 1 LAST PACK_TYPE 0402
J 0
(-1225 2625);
DISPLAY 0.617021 (-1225 2625);
PAINT SKYBLUE (-1225 2625);
FORCEPROP 0 LAST GROUP NI_I210&RJ45
J 0
(-1647 2587);
DISPLAY 0.638298 (-1647 2587);
PAINT BROWN (-1647 2587);
DISPLAY BOTH (-1647 2587);
FORCEPROP 1 LAST VALUE 33.2
J 0
(-1500 2675);
DISPLAY 0.617021 (-1500 2675);
PAINT SKYBLUE (-1500 2675);
FORCEPROP 1 LASTPIN (-1300 2750) $PN 2
J 0
(-1338 2762);
DISPLAY 0.617021 (-1338 2762);
PAINT ORANGE (-1338 2762);
FORCEPROP 1 LAST TOLERANCE 1%
J 0
(-1350 2675);
DISPLAY 0.617021 (-1350 2675);
PAINT SKYBLUE (-1350 2675);
FORCEPROP 1 LAST LOCATION R9E6
J 0
(-1675 2675);
DISPLAY 0.617021 (-1675 2675);
PAINT AQUA (-1675 2675);
FORCEPROP 1 LAST WATTAGE 1/16W
J 0
(-1250 2675);
DISPLAY 0.617021 (-1250 2675);
PAINT SKYBLUE (-1250 2675);
FORCEPROP 1 LASTPIN (-1500 2750) $PN 1
J 0
(-1488 2762);
DISPLAY 0.617021 (-1488 2762);
PAINT ORANGE (-1488 2762);
FORCEPROP 2 LAST CDS_LIB mstr_discrete
J 0
(-1400 2750);
PAINT ORANGE (-1400 2750);
DISPLAY INVISIBLE (-1400 2750);
FORCEPROP 2 LAST CDS_LOCATION R9E6
J 0
(-1450 2800);
DISPLAY 0.617021 (-1450 2800);
PAINT AQUA (-1450 2800);
DISPLAY INVISIBLE (-1450 2800);
FORCEPROP 2 LAST SEC_TYPE 0402
J 0
(-1450 2950);
DISPLAY 1.021277 (-1450 2950);
PAINT ORANGE (-1450 2950);
DISPLAY INVISIBLE (-1450 2950);
FORCEPROP 2 LAST BOM_COST NT_GBE_BASE
J 0
(-1450 2900);
DISPLAY 1.021277 (-1450 2900);
PAINT ORANGE (-1450 2900);
DISPLAY INVISIBLE (-1450 2900);
FORCEPROP 2 LAST SEC 1
J 0
(-1450 2950);
PAINT MONO (-1450 2950);
DISPLAY INVISIBLE (-1450 2950);
FORCEPROP 1 LAST PATH I17
J 0
(-1450 2900);
DISPLAY 0.978723 (-1450 2900);
PAINT WHITE (-1450 2900);
DISPLAY INVISIBLE (-1450 2900);
FORCEPROP 2 LAST ROOM NIC_SPRV
J 0
(-1450 2850);
DISPLAY 1.021277 (-1450 2850);
PAINT ORANGE (-1450 2850);
DISPLAY INVISIBLE (-1450 2850);
FORCEADD CAP_A..1
(-2475 3375);
FORCEPROP 1 LAST TOLERANCE 10%
J 0
(-2425 3325);
DISPLAY 0.617021 (-2425 3325);
PAINT SKYBLUE (-2425 3325);
FORCEPROP 1 LAST MATERIAL X7R
J 0
(-2425 3275);
DISPLAY 0.617021 (-2425 3275);
PAINT SKYBLUE (-2425 3275);
FORCEPROP 1 LASTPIN (-2475 3475) $PN 1
J 0
(-2465 3455);
DISPLAY 0.617021 (-2465 3455);
PAINT ORANGE (-2465 3455);
FORCEPROP 1 LAST VOLTAGE 16V
J 0
(-2425 3375);
DISPLAY 0.617021 (-2425 3375);
PAINT SKYBLUE (-2425 3375);
FORCEPROP 1 LAST VALUE 0.1UF
J 0
(-2425 3425);
DISPLAY 0.617021 (-2425 3425);
PAINT SKYBLUE (-2425 3425);
FORCEPROP 1 LAST PACK_TYPE 0402V
J 0
(-2425 3175);
DISPLAY 0.617021 (-2425 3175);
PAINT SKYBLUE (-2425 3175);
FORCEPROP 1 LASTPIN (-2475 3275) $PN 2
J 0
(-2465 3255);
DISPLAY 0.617021 (-2465 3255);
PAINT ORANGE (-2465 3255);
FORCEPROP 1 LAST LOCATION C1R25
J 0
(-2425 3475);
DISPLAY 0.617021 (-2425 3475);
PAINT AQUA (-2425 3475);
FORCEPROP 1 LAST PART_NUMBER A36096-030
J 0
(-2425 3225);
DISPLAY 0.617021 (-2425 3225);
PAINT BLUE (-2425 3225);
FORCEPROP 0 LAST GROUP NI_I210&RJ45
J 0
(-2422 3112);
DISPLAY 0.638298 (-2422 3112);
PAINT BROWN (-2422 3112);
DISPLAY BOTH (-2422 3112);
FORCEPROP 2 LAST CDS_LIB dev_discrete
J 0
(-2475 3375);
PAINT ORANGE (-2475 3375);
DISPLAY INVISIBLE (-2475 3375);
FORCEPROP 1 LAST PATH I3
J 0
(-2425 3525);
DISPLAY 0.978723 (-2425 3525);
PAINT WHITE (-2425 3525);
DISPLAY INVISIBLE (-2425 3525);
FORCEPROP 2 LAST ROOM NIC_SPRV
J 0
(-2425 3525);
DISPLAY 1.021277 (-2425 3525);
PAINT ORANGE (-2425 3525);
DISPLAY INVISIBLE (-2425 3525);
FORCEPROP 2 LAST CDS_LOCATION C1R25
J 0
(-2425 3475);
DISPLAY 0.617021 (-2425 3475);
PAINT AQUA (-2425 3475);
DISPLAY INVISIBLE (-2425 3475);
FORCEPROP 2 LAST CDS_SEC 1
J 0
(-2425 3525);
PAINT ORANGE (-2425 3525);
DISPLAY INVISIBLE (-2425 3525);
FORCEPROP 2 LAST SEC 1
J 0
(-2425 3575);
PAINT MONO (-2425 3575);
DISPLAY INVISIBLE (-2425 3575);
FORCEPROP 2 LAST SEC_TYPE 0402V
J 0
(-2425 3575);
DISPLAY 1.021277 (-2425 3575);
PAINT ORANGE (-2425 3575);
DISPLAY INVISIBLE (-2425 3575);
FORCEPROP 2 LAST BOM_COST NT_GBE_BASE
J 0
(-2425 3575);
DISPLAY 1.021277 (-2425 3575);
PAINT ORANGE (-2425 3575);
DISPLAY INVISIBLE (-2425 3575);
FORCEADD GND..1
(-2475 3100);
FORCEPROP 3 LASTPIN (-2475 3150) SIG_NAME GND\g
J 0
(-2465 3160);
DISPLAY 0.659574 (-2465 3160);
PAINT MONO (-2465 3160);
DISPLAY INVISIBLE (-2465 3160);
FORCEPROP 1 LAST VOLTAGE 0.0V
J 0
(-2520 3057);
DISPLAY 0.340426 (-2520 3057);
PAINT SKYBLUE (-2520 3057);
DISPLAY INVISIBLE (-2520 3057);
FORCEPROP 1 LAST SIZE 1B
J 0
(-2400 3050);
DISPLAY 0.872340 (-2400 3050);
PAINT AQUA (-2400 3050);
DISPLAY INVISIBLE (-2400 3050);
FORCEPROP 2 LAST CDS_LIB mstr_symbols
J 0
(-2475 3100);
PAINT ORANGE (-2475 3100);
DISPLAY INVISIBLE (-2475 3100);
FORCEPROP 1 LAST PATH I4
J 0
(-2400 3100);
DISPLAY 0.872340 (-2400 3100);
PAINT AQUA (-2400 3100);
DISPLAY INVISIBLE (-2400 3100);
FORCEPROP 1 LAST BODY_TYPE PLUMBING
J 0
(-2520 3057);
DISPLAY 0.340426 (-2520 3057);
PAINT GREEN (-2520 3057);
DISPLAY INVISIBLE (-2520 3057);
FORCEPROP 1 LAST HDL_POWER GND
J 0
(-2475 3250);
DISPLAY 0.872340 (-2475 3250);
PAINT GREEN (-2475 3250);
DISPLAY INVISIBLE (-2475 3250);
FORCEADD OFFPAGE..1
(-4475 2750);
FORCEPROP 2 LAST $XR0 139 
J 0
(-4727 2750);
DISPLAY 0.638298 (-4727 2750);
PAINT MONO (-4727 2750);
FORCEPROP 2 LAST CDS_LIB mstr_standard
J 0
(-4475 2750);
PAINT ORANGE (-4475 2750);
DISPLAY INVISIBLE (-4475 2750);
FORCEPROP 2 LAST PATH I5
J 0
(-4425 2825);
DISPLAY 1.021277 (-4425 2825);
PAINT ORANGE (-4425 2825);
DISPLAY INVISIBLE (-4425 2825);
FORCEPROP 1 LAST OFFPAGE TRUE
J 0
(-4150 2625);
DISPLAY 0.872340 (-4150 2625);
PAINT GREEN (-4150 2625);
DISPLAY INVISIBLE (-4150 2625);
FORCEPROP 1 LAST COMMENT_BODY TRUE
J 0
(-4350 2650);
DISPLAY 0.872340 (-4350 2650);
PAINT GREEN (-4350 2650);
DISPLAY INVISIBLE (-4350 2650);
FORCEADD OFFPAGE..1
(-4475 2650);
FORCEPROP 2 LAST $XR0 139 
J 0
(-4727 2650);
DISPLAY 0.638298 (-4727 2650);
PAINT MONO (-4727 2650);
FORCEPROP 2 LAST PATH I6
J 0
(-4425 2725);
DISPLAY 1.021277 (-4425 2725);
PAINT ORANGE (-4425 2725);
DISPLAY INVISIBLE (-4425 2725);
FORCEPROP 2 LAST CDS_LIB mstr_standard
J 0
(-4475 2650);
PAINT ORANGE (-4475 2650);
DISPLAY INVISIBLE (-4475 2650);
FORCEPROP 1 LAST OFFPAGE TRUE
J 0
(-4150 2525);
DISPLAY 0.872340 (-4150 2525);
PAINT GREEN (-4150 2525);
DISPLAY INVISIBLE (-4150 2525);
FORCEPROP 1 LAST COMMENT_BODY TRUE
J 0
(-4350 2550);
DISPLAY 0.872340 (-4350 2550);
PAINT GREEN (-4350 2550);
DISPLAY INVISIBLE (-4350 2550);
FORCEADD OFFPAGE..1
(-4475 2550);
FORCEPROP 2 LAST CDS_LIB mstr_standard
J 0
(-4475 2550);
PAINT ORANGE (-4475 2550);
DISPLAY INVISIBLE (-4475 2550);
FORCEPROP 2 LAST PATH I7
J 0
(-4425 2625);
DISPLAY 1.021277 (-4425 2625);
PAINT ORANGE (-4425 2625);
DISPLAY INVISIBLE (-4425 2625);
FORCEPROP 1 LAST OFFPAGE TRUE
J 0
(-4150 2425);
DISPLAY 0.872340 (-4150 2425);
PAINT GREEN (-4150 2425);
DISPLAY INVISIBLE (-4150 2425);
FORCEPROP 1 LAST COMMENT_BODY TRUE
J 0
(-4350 2450);
DISPLAY 0.872340 (-4350 2450);
PAINT GREEN (-4350 2450);
DISPLAY INVISIBLE (-4350 2450);
FORCEPROP 2 LAST $XR0 139 
J 0
(-4901 2550);
DISPLAY 0.638298 (-4901 2550);
PAINT MONO (-4901 2550);
DISPLAY INVISIBLE (-4901 2550);
FORCEADD OFFPAGE..2
(-600 2750);
FORCEPROP 2 LAST $XR0 139 
J 0
(-411 2750);
DISPLAY 0.638298 (-411 2750);
PAINT MONO (-411 2750);
FORCEPROP 2 LAST CDS_LIB mstr_standard
J 0
(-600 2750);
PAINT ORANGE (-600 2750);
DISPLAY INVISIBLE (-600 2750);
FORCEPROP 2 LAST PATH I8
J 0
(-550 2825);
DISPLAY 1.021277 (-550 2825);
PAINT ORANGE (-550 2825);
DISPLAY INVISIBLE (-550 2825);
FORCEPROP 1 LAST OFFPAGE TRUE
J 0
(-275 2625);
DISPLAY 0.872340 (-275 2625);
PAINT GREEN (-275 2625);
DISPLAY INVISIBLE (-275 2625);
FORCEPROP 1 LAST COMMENT_BODY TRUE
J 0
(-645 2655);
DISPLAY 0.872340 (-645 2655);
PAINT GREEN (-645 2655);
DISPLAY INVISIBLE (-645 2655);
FORCEADD GND..1
(-1900 2175);
FORCEPROP 3 LASTPIN (-1900 2225) SIG_NAME GND\g
J 0
(-1890 2235);
DISPLAY 0.659574 (-1890 2235);
PAINT MONO (-1890 2235);
DISPLAY INVISIBLE (-1890 2235);
FORCEPROP 1 LAST VOLTAGE 0.0V
J 0
(-1945 2132);
DISPLAY 0.340426 (-1945 2132);
PAINT SKYBLUE (-1945 2132);
DISPLAY INVISIBLE (-1945 2132);
FORCEPROP 1 LAST SIZE 1B
J 0
(-1825 2125);
DISPLAY 0.872340 (-1825 2125);
PAINT AQUA (-1825 2125);
DISPLAY INVISIBLE (-1825 2125);
FORCEPROP 2 LAST CDS_LIB mstr_symbols
J 0
(-1900 2175);
PAINT ORANGE (-1900 2175);
DISPLAY INVISIBLE (-1900 2175);
FORCEPROP 1 LAST PATH I9
J 0
(-1825 2175);
DISPLAY 0.872340 (-1825 2175);
PAINT AQUA (-1825 2175);
DISPLAY INVISIBLE (-1825 2175);
FORCEPROP 1 LAST BODY_TYPE PLUMBING
J 0
(-1945 2132);
DISPLAY 0.340426 (-1945 2132);
PAINT GREEN (-1945 2132);
DISPLAY INVISIBLE (-1945 2132);
FORCEPROP 1 LAST HDL_POWER GND
J 0
(-1900 2325);
DISPLAY 0.872340 (-1900 2325);
PAINT GREEN (-1900 2325);
DISPLAY INVISIBLE (-1900 2325);
FORCEADD INTEL_CORP_BPAGE..1
(-50 0);
FORCEPROP 1 LAST CDS_CON_LAST_MODIFIED Fri Jun 16 17:48:53 2017
J 0
(-1475 325);
DISPLAY 0.659574 (-1475 325);
PAINT GREEN (-1475 325);
DISPLAY INVISIBLE (-1475 325);
FORCEPROP 1 LAST CUSTOM_TXT_CDS <CURRENT_DESIGN_SHEET> OF <TOTAL_DESIGN_SHEETS>
J 0
(-550 25);
PAINT ORANGE (-550 25);
FORCEPROP 2 LAST CUSTOM_TXT_CDS <XR_PAGE_TITLE>
J 0
(-7940 5250);
DISPLAY 0.638298 (-7940 5250);
PAINT PINK (-7940 5250);
DISPLAY INVISIBLE (-7940 5250);
FORCEPROP 2 LAST CUSTOM_TXT_CDS <CON_LAST_MODIFIED>
J 0
(-4050 100);
DISPLAY 0.957447 (-4050 100);
PAINT ORANGE (-4050 100);
FORCEPROP 1 LAST SCH_TITLE LAN SPRINGVILLE I210 (2/3)
J 0
(-8000 50);
DISPLAY 1.212766 (-8000 50);
PAINT GREEN (-8000 50);
FORCEPROP 2 LAST CDS_LIB mstr_symbols
J 0
(-50 0);
DISPLAY 0.489362 (-50 0);
PAINT ORANGE (-50 0);
DISPLAY INVISIBLE (-50 0);
FORCEPROP 2 LAST PAGE_BORDER TRUE
J 0
(-7940 5250);
DISPLAY 0.638298 (-7940 5250);
PAINT PINK (-7940 5250);
DISPLAY INVISIBLE (-7940 5250);
FORCEPROP 1 LAST COMMENT_BODY TRUE
J 0
(-38 12);
DISPLAY 0.319149 (-38 12);
PAINT GREEN (-38 12);
DISPLAY INVISIBLE (-38 12);
FORCEPROP 2 LAST CDS_XR_PAGE_TITLE CR-140 : @BASEBOARD_FAB2_LIB.BASEBOARD_FAB2(SCH_1):PAGE140
J 0
(-7940 5250);
DISPLAY 0.638298 (-7940 5250);
PAINT PINK (-7940 5250);
DISPLAY INVISIBLE (-7940 5250);
FORCEADD DNS..2
(-3820 2345);
PAINT RED (-3820 2345);
FORCEPROP 2 LAST CDS_LIB mstr_misc
J 0
(-3820 2345);
PAINT ORANGE (-3820 2345);
DISPLAY INVISIBLE (-3820 2345);
FORCEPROP 1 LAST COMMENT_BODY TRUE
R 1
J 0
(-3745 2120);
DISPLAY 0.872340 (-3745 2120);
PAINT GREEN (-3745 2120);
DISPLAY INVISIBLE (-3745 2120);
WIRE 16 -1 (-3950 3575)(-3950 3525);
WIRE 16 -1 (-3950 3525)(-3550 3525);
WIRE 16 -1 (-3950 3400)(-3950 3525);
WIRE 16 -1 (-3550 3525)(-3200 3525);
WIRE 16 -1 (-3550 3400)(-3550 3525);
WIRE 16 -1 (-3200 3525)(-2825 3525);
WIRE 16 -1 (-3200 3400)(-3200 3525);
WIRE 16 -1 (-2475 3525)(-2825 3525);
WIRE 16 -1 (-2825 3525)(-2825 2850);
WIRE 16 -1 (-2825 2850)(-2700 2850);
WIRE 16 -1 (-2475 3475)(-2475 3525);
WIRE 16 -1 (-3825 2125)(-3825 2250);
WIRE 16 -1 (-2475 3150)(-2475 3275);
WIRE 16 -1 (-1900 2225)(-1900 2500);
WIRE 16 -1 (-1900 2500)(-2000 2500);
WIRE 16 -1 (-3200 2600)(-2700 2600);
FORCEPROP 2 LAST SIG_NAME PU_NV_HOLD_N
J 0
(-3060 2610);
DISPLAY 0.617021 (-3060 2610);
PAINT ORANGE (-3060 2610);
FORCEPROP 2 LASTPROP $XRERR UNIQUE?
J 0
(-3300 2610);
DISPLAY 0.638298 (-3300 2610);
PAINT MONO (-3300 2610);
DISPLAY INVISIBLE (-3300 2610);
WIRE 16 -1 (-3200 3200)(-3200 2600);
WIRE 16 -1 (-3950 2750)(-4425 2750);
FORCEPROP 2 LAST SIG_NAME SPI_NIC_MOSI
J 0
(-4425 2760);
DISPLAY 0.617021 (-4425 2760);
PAINT ORANGE (-4425 2760);
WIRE 16 -1 (-3950 3200)(-3950 2750);
WIRE 16 -1 (-3825 2750)(-3950 2750);
WIRE 16 -1 (-2700 2750)(-3825 2750);
WIRE 16 -1 (-3825 2450)(-3825 2750);
WIRE 16 -1 (-3550 2500)(-2700 2500);
FORCEPROP 2 LAST SIG_NAME PU_NV_WP_N
J 0
(-3035 2510);
DISPLAY 0.617021 (-3035 2510);
PAINT ORANGE (-3035 2510);
FORCEPROP 2 LASTPROP $XRERR UNIQUE?
J 0
(-3275 2510);
DISPLAY 0.638298 (-3275 2510);
PAINT MONO (-3275 2510);
DISPLAY INVISIBLE (-3275 2510);
WIRE 16 -1 (-3550 3200)(-3550 2500);
WIRE 16 -1 (-2000 2750)(-1500 2750);
FORCEPROP 2 LAST SIG_NAME SPI_NIC_MISO_R
J 0
(-1885 2760);
DISPLAY 0.617021 (-1885 2760);
PAINT ORANGE (-1885 2760);
FORCEPROP 2 LASTPROP $XRERR UNIQUE?
J 0
(-2125 2760);
DISPLAY 0.638298 (-2125 2760);
PAINT MONO (-2125 2760);
DISPLAY INVISIBLE (-2125 2760);
WIRE 16 -1 (-1300 2750)(-650 2750);
FORCEPROP 2 LAST SIG_NAME SPI_NIC_MISO
J 0
(-1160 2760);
DISPLAY 0.617021 (-1160 2760);
PAINT ORANGE (-1160 2760);
WIRE 16 -1 (-2700 2650)(-4425 2650);
FORCEPROP 2 LAST SIG_NAME SPI_NIC_SCLK
J 0
(-4425 2660);
DISPLAY 0.617021 (-4425 2660);
PAINT ORANGE (-4425 2660);
WIRE 16 -1 (-2700 2550)(-4425 2550);
FORCEPROP 2 LAST SIG_NAME SPI_NIC_CS_N
J 0
(-4425 2560);
DISPLAY 0.617021 (-4425 2560);
PAINT ORANGE (-4425 2560);
DOT 1 (-3825 2750);
DOT 1 (-3950 2750);
DOT 1 (-2825 3525);
DOT 1 (-3200 3525);
DOT 1 (-3550 3525);
DOT 1 (-3950 3525);
FORCENOTE
$CDS_IMAGE|Crescent_City_RMII_Block_0.JPG|2082|4000
(-6725 2500) 0;
DISPLAY LEFT (-6725 2500);
QUIT
